# S9S_MB_2U (Grand Teton) — schematic netlist excerpt (pin names and nets, part order shuffled) for the footprints in the layout excerpt that follows; sources: Cadence DE-HDL packaged netlist, KiCad conversion of 03242023_DA0F0TMBIJ0_F0T_Motherboard_J_brd_V01_OCP.brd

PR3846  Q_RES  1.33K 1% EMPTY  pkg 0402LF  page 157 : A = GND ; B = P3V3_OCP_ILIMIT_1
R3682  Q_RES  0 5% CHIP  pkg 0402LF  page 250 : A = P3V3_AUX_ADC ; B = P3V3_AUX_ADC_TIC
H124  HOLE  EMPTY  pkg TH  page 311 : \1\ = NC

(kicad_pcb
	(version 20260206)
	(generator "pcbnew")
	(generator_version "10.0")
	(general
		(thickness 1.6)
		(legacy_teardrops no)
	)
	(paper "A4")
	(title_block
		(title "03242023_DA0F0TMBIJ0_F0T_Motherboard_J_brd_V01_OCP.brd")
		(comment 1 "Grand Teton / footprints 3766-3768 of 6105")
	)
	(layers
		(0 "F.Cu" signal "TOP")
		(4 "In1.Cu" signal "GND")
		(6 "In2.Cu" signal "IN1")
		(8 "In3.Cu" signal "GND1")
		(10 "In4.Cu" signal "IN2")
		(12 "In5.Cu" signal "GND2")
		(14 "In6.Cu" signal "IN3")
		(16 "In7.Cu" signal "GND3")
		(18 "In8.Cu" signal "VCC")
		(20 "In9.Cu" signal "VCC1")
		(22 "In10.Cu" signal "GND4")
		(24 "In11.Cu" signal "IN4")
		(26 "In12.Cu" signal "GND5")
		(28 "In13.Cu" signal "IN5")
		(30 "In14.Cu" signal "GND6")
		(32 "In15.Cu" signal "IN6")
		(34 "In16.Cu" signal "GND7")
		(2 "B.Cu" signal "BOTTOM")
		(9 "F.Adhes" user "F.Adhesive")
		(11 "B.Adhes" user "B.Adhesive")
		(13 "F.Paste" user "Package Geometry/Pastemask Top")
		(15 "B.Paste" user "Package Geometry/Pastemask Bottom")
		(5 "F.SilkS" user "Ref Des/Silkscreen Top")
		(7 "B.SilkS" user "Ref Des/Silkscreen Bottom")
		(1 "F.Mask" user "Board Geometry/Soldermask Top")
		(3 "B.Mask" user "Board Geometry/Soldermask Bottom")
		(17 "Dwgs.User" user "User.Drawings")
		(19 "Cmts.User" user "User.Comments")
		(21 "Eco1.User" user "User.Eco1")
		(23 "Eco2.User" user "User.Eco2")
		(25 "Edge.Cuts" user "Board Geometry/Outline")
		(27 "Margin" user)
		(31 "F.CrtYd" user "Package Geometry/Place Bound Top")
		(29 "B.CrtYd" user "Package Geometry/Place Bound Bottom")
		(35 "F.Fab" user "Ref Des/Assembly Top")
		(33 "B.Fab" user "Ref Des/Assembly Bottom")
	)
	(footprint ""
		(layer "F.Cu")
		(at 39.827454 -107.031282 180)
		(property "Reference" "R3682"
			(at 0 0 180)
			(layer "F.SilkS")
			(hide yes)
			(effects
				(font
					(size 1.27 1.27)
				)
			)
		)
		(property "Value" ""
			(at 0 0 180)
			(layer "F.Fab")
			(effects
				(font
					(size 1.27 1.27)
				)
			)
		)
		(duplicate_pad_numbers_are_jumpers no)
		(fp_line
			(start 0.7874 0.4064)
			(end -0.7874 0.4064)
			(stroke
				(width 0.1524)
				(type default)
			)
			(layer "F.SilkS")
		)
		(fp_line
			(start 0.7874 -0.4064)
			(end 0.7874 0.4064)
			(stroke
				(width 0.1524)
				(type default)
			)
			(layer "F.SilkS")
		)
		(fp_line
			(start -0.7874 0.4064)
			(end -0.7874 -0.4064)
			(stroke
				(width 0.1524)
				(type default)
			)
			(layer "F.SilkS")
		)
		(fp_line
			(start -0.7874 -0.4064)
			(end 0.7874 -0.4064)
			(stroke
				(width 0.1524)
				(type default)
			)
			(layer "F.SilkS")
		)
		(fp_line
			(start 0.67945 0.3048)
			(end 0.120396 0.3048)
			(stroke
				(width 0.1)
				(type default)
			)
			(layer "F.Fab")
		)
		(fp_line
			(start 0.67945 -0.3048)
			(end 0.67945 0.3048)
			(stroke
				(width 0.1)
				(type default)
			)
			(layer "F.Fab")
		)
		(fp_line
			(start 0.12065 -0.2794)
			(end 0.12065 -0.3048)
			(stroke
				(width 0.1)
				(type default)
			)
			(layer "F.Fab")
		)
		(fp_line
			(start 0.12065 -0.3048)
			(end 0.67945 -0.3048)
			(stroke
				(width 0.1)
				(type default)
			)
			(layer "F.Fab")
		)
		(fp_line
			(start 0.120396 0.3048)
			(end 0.120396 0.2794)
			(stroke
				(width 0.1)
				(type default)
			)
			(layer "F.Fab")
		)
		(fp_line
			(start 0.120396 0.2794)
			(end -0.12065 0.2794)
			(stroke
				(width 0.1)
				(type default)
			)
			(layer "F.Fab")
		)
		(fp_line
			(start -0.12065 0.3048)
			(end -0.67945 0.3048)
			(stroke
				(width 0.1)
				(type default)
			)
			(layer "F.Fab")
		)
		(fp_line
			(start -0.12065 0.2794)
			(end -0.12065 0.3048)
			(stroke
				(width 0.1)
				(type default)
			)
			(layer "F.Fab")
		)
		(fp_line
			(start -0.12065 -0.2794)
			(end 0.12065 -0.2794)
			(stroke
				(width 0.1)
				(type default)
			)
			(layer "F.Fab")
		)
		(fp_line
			(start -0.12065 -0.305054)
			(end -0.12065 -0.2794)
			(stroke
				(width 0.1)
				(type default)
			)
			(layer "F.Fab")
		)
		(fp_line
			(start -0.67945 0.3048)
			(end -0.67945 -0.305054)
			(stroke
				(width 0.1)
				(type default)
			)
			(layer "F.Fab")
		)
		(fp_line
			(start -0.67945 -0.305054)
			(end -0.12065 -0.305054)
			(stroke
				(width 0.1)
				(type default)
			)
			(layer "F.Fab")
		)
		(pad "1" smd rect
			(at -0.40005 0)
			(size 0.4572 0.508)
			(layers "F.Cu" "F.Mask" "F.Paste")
			(net "P3V3_AUX_ADC")
		)
		(pad "2" smd rect
			(at 0.40005 0)
			(size 0.4572 0.508)
			(layers "F.Cu" "F.Mask" "F.Paste")
			(net "P3V3_AUX_ADC_TIC")
		)
	)
	(footprint ""
		(layer "F.Cu")
		(at 419.76294 -101.270308 90)
		(property "Reference" "PR3846"
			(at 0 0 90)
			(layer "F.SilkS")
			(hide yes)
			(effects
				(font
					(size 1.27 1.27)
				)
			)
		)
		(property "Value" ""
			(at 0 0 90)
			(layer "F.Fab")
			(effects
				(font
					(size 1.27 1.27)
				)
			)
		)
		(duplicate_pad_numbers_are_jumpers no)
		(fp_line
			(start 0.7874 -0.4064)
			(end 0.7874 0.4064)
			(stroke
				(width 0.1524)
				(type default)
			)
			(layer "F.SilkS")
		)
		(fp_line
			(start -0.7874 -0.4064)
			(end 0.7874 -0.4064)
			(stroke
				(width 0.1524)
				(type default)
			)
			(layer "F.SilkS")
		)
		(fp_line
			(start 0.7874 0.4064)
			(end -0.7874 0.4064)
			(stroke
				(width 0.1524)
				(type default)
			)
			(layer "F.SilkS")
		)
		(fp_line
			(start -0.7874 0.4064)
			(end -0.7874 -0.4064)
			(stroke
				(width 0.1524)
				(type default)
			)
			(layer "F.SilkS")
		)
		(fp_line
			(start -0.12065 -0.305054)
			(end -0.12065 -0.2794)
			(stroke
				(width 0.1)
				(type default)
			)
			(layer "F.Fab")
		)
		(fp_line
			(start -0.67945 -0.305054)
			(end -0.12065 -0.305054)
			(stroke
				(width 0.1)
				(type default)
			)
			(layer "F.Fab")
		)
		(fp_line
			(start 0.67945 -0.3048)
			(end 0.67945 0.3048)
			(stroke
				(width 0.1)
				(type default)
			)
			(layer "F.Fab")
		)
		(fp_line
			(start 0.12065 -0.3048)
			(end 0.67945 -0.3048)
			(stroke
				(width 0.1)
				(type default)
			)
			(layer "F.Fab")
		)
		(fp_line
			(start 0.12065 -0.2794)
			(end 0.12065 -0.3048)
			(stroke
				(width 0.1)
				(type default)
			)
			(layer "F.Fab")
		)
		(fp_line
			(start -0.12065 -0.2794)
			(end 0.12065 -0.2794)
			(stroke
				(width 0.1)
				(type default)
			)
			(layer "F.Fab")
		)
		(fp_line
			(start 0.120396 0.2794)
			(end -0.12065 0.2794)
			(stroke
				(width 0.1)
				(type default)
			)
			(layer "F.Fab")
		)
		(fp_line
			(start -0.12065 0.2794)
			(end -0.12065 0.3048)
			(stroke
				(width 0.1)
				(type default)
			)
			(layer "F.Fab")
		)
		(fp_line
			(start 0.67945 0.3048)
			(end 0.120396 0.3048)
			(stroke
				(width 0.1)
				(type default)
			)
			(layer "F.Fab")
		)
		(fp_line
			(start 0.120396 0.3048)
			(end 0.120396 0.2794)
			(stroke
				(width 0.1)
				(type default)
			)
			(layer "F.Fab")
		)
		(fp_line
			(start -0.12065 0.3048)
			(end -0.67945 0.3048)
			(stroke
				(width 0.1)
				(type default)
			)
			(layer "F.Fab")
		)
		(fp_line
			(start -0.67945 0.3048)
			(end -0.67945 -0.305054)
			(stroke
				(width 0.1)
				(type default)
			)
			(layer "F.Fab")
		)
		(pad "1" smd circle
			(at -0.40005 0 90)
			(size 0 0)
			(layers "F.Cu" "F.Mask" "F.Paste")
			(net "GND")
		)
		(pad "2" smd circle
			(at 0.40005 0 90)
			(size 0 0)
			(layers "F.Cu" "F.Mask" "F.Paste")
			(net "P3V3_OCP_ILIMIT_1")
		)
	)
	(footprint ""
		(layer "F.Cu")
		(at 193.954654 -153.774902)
		(property "Reference" "H124"
			(at 1.36144 6.74243 0)
			(unlocked yes)
			(layer "F.SilkS")
			(effects
				(font
					(size 0.7874 0.5842)
					(thickness 0.1524)
				)
				(justify left)
			)
		)
		(property "Value" ""
			(at 0 0 0)
			(layer "F.Fab")
			(effects
				(font
					(size 1.27 1.27)
				)
			)
		)
		(duplicate_pad_numbers_are_jumpers no)
		(fp_circle
			(center 0 0)
			(end 5.8166 0)
			(stroke
				(width 0.1524)
				(type default)
			)
			(fill no)
			(layer "F.SilkS")
		)
		(fp_circle
			(center 0 0)
			(end 5.8166 0)
			(stroke
				(width 0.1524)
				(type default)
			)
			(fill no)
			(layer "B.SilkS")
		)
		(fp_circle
			(center 0 0)
			(end 5.8166 0)
			(stroke
				(width 0.1)
				(type default)
			)
			(fill no)
			(layer "B.Fab")
		)
		(fp_circle
			(center 0 0)
			(end 5.8166 0)
			(stroke
				(width 0.1)
				(type default)
			)
			(fill no)
			(layer "F.Fab")
		)
		(pad "" np_thru_hole circle
			(at 0 0)
			(size 10.0076 10.0076)
			(drill 10.0076)
			(layers "*.Cu" "*.Mask")
			(clearance 0.381)
			(thermal_gap 0.381)
		)
	)
)
